(kicad_pcb
	(version 20241229)
	(generator "pcbnew")
	(generator_version "9.0")
	(general
		(thickness 1.61)
		(legacy_teardrops no)
	)
	(paper "A3")
	(title_block
		(title "RDIMM DDR5 Tester")
		(date "2026-05-21")
		(rev "2.2.0")
		(company "Antmicro")
		(comment 9 "footprints 62-65 of 796")
	)
	(layers
		(0 "F.Cu" signal)
		(4 "In1.Cu" power)
		(6 "In2.Cu" mixed)
		(8 "In3.Cu" power)
		(10 "In4.Cu" mixed)
		(12 "In5.Cu" power)
		(14 "In6.Cu" mixed)
		(16 "In7.Cu" power)
		(18 "In8.Cu" power)
		(20 "In9.Cu" mixed)
		(22 "In10.Cu" power)
		(2 "B.Cu" signal)
		(9 "F.Adhes" user "F.Adhesive")
		(11 "B.Adhes" user "B.Adhesive")
		(13 "F.Paste" user)
		(15 "B.Paste" user)
		(5 "F.SilkS" user "F.Silkscreen")
		(7 "B.SilkS" user "B.Silkscreen")
		(1 "F.Mask" user)
		(3 "B.Mask" user)
		(17 "Dwgs.User" user "User.Drawings")
		(19 "Cmts.User" user "User.Comments")
		(21 "Eco1.User" user "User.Eco1")
		(23 "Eco2.User" user "User.Eco2")
		(25 "Edge.Cuts" user)
		(27 "Margin" user)
		(31 "F.CrtYd" user "F.Courtyard")
		(29 "B.CrtYd" user "B.Courtyard")
		(35 "F.Fab" user)
		(33 "B.Fab" user)
	)
	(footprint "antmicro-footprints:R_0402_1005Metric"
		(layer "F.Cu")
		(at 145.124499 173.249 -90)
		(descr "Resistor SMD 0402")
		(tags "resistor SMD 0402")
		(property "Reference" "R95"
			(at 0.931 -0.465501 90)
			(layer "F.SilkS")
			(effects
				(font
					(size 0.7 0.7)
					(thickness 0.15)
				)
				(justify right bottom)
			)
		)
		(property "Value" "R_4k7_0402"
			(at -1.011843 1.772047 90)
			(layer "F.Fab")
			(effects
				(font
					(size 0.7 0.7)
					(thickness 0.15)
				)
				(justify right bottom)
			)
		)
		(property "Datasheet" "https://www.bourns.com/docs/product-datasheets/cr.pdf"
			(at 0 0 270)
			(layer "F.Fab")
			(hide yes)
			(effects
				(font
					(size 1.27 1.27)
					(thickness 0.15)
				)
			)
		)
		(property "Manufacturer" "Bourns"
			(at 0 0 270)
			(unlocked yes)
			(layer "F.Fab")
			(hide yes)
			(effects
				(font
					(size 1 1)
					(thickness 0.15)
				)
			)
		)
		(property "MPN" "CR0402-FX-4701GLF"
			(at 0 0 270)
			(unlocked yes)
			(layer "F.Fab")
			(hide yes)
			(effects
				(font
					(size 1 1)
					(thickness 0.15)
				)
			)
		)
		(property "Val" "4k7"
			(at 0 0 270)
			(unlocked yes)
			(layer "F.Fab")
			(hide yes)
			(effects
				(font
					(size 1 1)
					(thickness 0.15)
				)
			)
		)
		(property "License" "Apache-2.0"
			(at 0 0 270)
			(unlocked yes)
			(layer "F.Fab")
			(hide yes)
			(effects
				(font
					(size 1 1)
					(thickness 0.15)
				)
			)
		)
		(property "Author" "Antmicro"
			(at 0 0 270)
			(unlocked yes)
			(layer "F.Fab")
			(hide yes)
			(effects
				(font
					(size 1 1)
					(thickness 0.15)
				)
			)
		)
		(property "Tolerance" "1%"
			(at 0 0 270)
			(unlocked yes)
			(layer "F.Fab")
			(hide yes)
			(effects
				(font
					(size 1 1)
					(thickness 0.15)
				)
			)
		)
		(sheetname "/Debug FTDI + VNA/")
		(sheetfile "debug-ftdi.kicad_sch")
		(attr smd)
		(fp_rect
			(start -0.925 -0.47)
			(end 0.925 0.47)
			(stroke
				(width 0.05)
				(type default)
			)
			(fill no)
			(layer "F.CrtYd")
		)
		(fp_rect
			(start -0.5 -0.25)
			(end 0.5 0.25)
			(stroke
				(width 0.15)
				(type solid)
			)
			(fill no)
			(layer "F.Fab")
		)
		(fp_text user "${REFERENCE}"
			(at -0.95 3.168 270)
			(layer "F.Fab")
			(effects
				(font
					(size 0.7 0.7)
					(thickness 0.15)
				)
				(justify left bottom)
			)
		)
		(fp_text user "License: Apache-2.0"
			(at -0.95 5.169 270)
			(layer "F.Fab")
			(effects
				(font
					(size 0.7 0.7)
					(thickness 0.15)
				)
				(justify left bottom)
			)
		)
		(fp_text user "Author: Antmicro"
			(at -0.95 4.169 270)
			(layer "F.Fab")
			(effects
				(font
					(size 0.7 0.7)
					(thickness 0.15)
				)
				(justify left bottom)
			)
		)
		(pad "1" smd roundrect
			(at -0.48 0 270)
			(size 0.59 0.64)
			(layers "F.Cu" "F.Mask" "F.Paste")
			(roundrect_rratio 0.25)
			(net 38 "+3V3_AON")
			(pintype "passive")
		)
		(pad "2" smd roundrect
			(at 0.48 0 270)
			(size 0.59 0.64)
			(layers "F.Cu" "F.Mask" "F.Paste")
			(roundrect_rratio 0.25)
			(net 527 "/Debug FTDI + VNA/FTDI.SDA")
			(pintype "passive")
		)
	)
	(footprint "antmicro-footprints:NetTie-2_SMD_Pad0.127mm"
		(layer "F.Cu")
		(at 246.877 160.15)
		(descr "Net tie, 2 pin, 0.127mm  SMD pads")
		(tags "net tie")
		(property "Reference" "NT5"
			(at -0.128 -1.345 0)
			(layer "F.SilkS")
			(hide yes)
			(effects
				(font
					(size 0.7 0.7)
					(thickness 0.15)
				)
				(justify left bottom)
			)
		)
		(property "Value" "Net-Tie_P0.127mm"
			(at 0 1.199 0)
			(layer "F.Fab")
			(effects
				(font
					(size 0.7 0.7)
					(thickness 0.15)
				)
				(justify left bottom)
			)
		)
		(property "MPN" ""
			(at 0 0 0)
			(unlocked yes)
			(layer "F.Fab")
			(hide yes)
			(effects
				(font
					(size 1 1)
					(thickness 0.15)
				)
			)
		)
		(property "Manufacturer" ""
			(at 0 0 0)
			(unlocked yes)
			(layer "F.Fab")
			(hide yes)
			(effects
				(font
					(size 1 1)
					(thickness 0.15)
				)
			)
		)
		(property "Author" "Antmicro"
			(at 0 0 0)
			(unlocked yes)
			(layer "F.Fab")
			(hide yes)
			(effects
				(font
					(size 1 1)
					(thickness 0.15)
				)
			)
		)
		(property "License" "Apache-2.0"
			(at 0 0 0)
			(unlocked yes)
			(layer "F.Fab")
			(hide yes)
			(effects
				(font
					(size 1 1)
					(thickness 0.15)
				)
			)
		)
		(property ki_fp_filters "Net*Tie*")
		(sheetname "/Supply/DC-DC IO/")
		(sheetfile "dc-dc-io.kicad_sch")
		(attr through_hole exclude_from_pos_files exclude_from_bom)
		(net_tie_pad_groups "1, 2")
		(fp_poly
			(pts
				(xy -0.0635 -0.0635) (xy 0.0625 -0.0635) (xy 0.0625 0.0635) (xy -0.0635 0.0635)
			)
			(stroke
				(width 0)
				(type solid)
			)
			(fill yes)
			(layer "F.Cu")
		)
		(fp_poly
			(pts
				(xy 0.2 -0.16) (xy 0.29 -0.07) (xy 0.29 0.07) (xy 0.2 0.16) (xy -0.2 0.16) (xy -0.29 0.07) (xy -0.29 -0.06)
				(xy -0.19 -0.16)
			)
			(stroke
				(width 0.05)
				(type solid)
			)
			(fill no)
			(layer "F.CrtYd")
		)
		(fp_text user "${REFERENCE}"
			(at -0.128 3.2 0)
			(layer "F.Fab")
			(effects
				(font
					(size 0.7 0.7)
					(thickness 0.15)
				)
				(justify left bottom)
			)
		)
		(fp_text user "Author: Antmicro"
			(at -0.128 4.4 0)
			(layer "F.Fab")
			(effects
				(font
					(size 0.7 0.7)
					(thickness 0.15)
				)
				(justify left bottom)
			)
		)
		(fp_text user "License: Apache-2.0"
			(at -0.128 5.6 0)
			(layer "F.Fab")
			(effects
				(font
					(size 0.7 0.7)
					(thickness 0.15)
				)
				(justify left bottom)
			)
		)
		(pad "1" smd roundrect
			(at -0.127 0 180)
			(size 0.127 0.127)
			(layers "F.Cu")
			(roundrect_rratio 0.5)
			(chamfer_ratio 0)
			(chamfer top_left bottom_left)
			(net 685 "/Supply/DC-DC IO/3V3_SEN_+")
			(pinfunction "1")
			(pintype "passive")
		)
		(pad "2" smd roundrect
			(at 0.126 0)
			(size 0.127 0.127)
			(layers "F.Cu")
			(roundrect_rratio 0.5)
			(chamfer_ratio 0)
			(chamfer top_left bottom_left)
			(net 45 "/Supply/DC-DC IO/3V3_local")
			(pinfunction "2")
			(pintype "passive")
		)
	)
	(footprint "antmicro-footprints:RJ45_ARJM11B1-502-AB-EW2_Horizontal"
		(layer "F.Cu")
		(at 118.114999 120.247487 -90)
		(descr "ARJM11B1-502-AB-EW2 RJ45 JACK")
		(property "Reference" "J6"
			(at -2.35 -2.3 270)
			(layer "F.SilkS")
			(effects
				(font
					(size 0.7 0.7)
					(thickness 0.15)
				)
				(justify left bottom)
			)
		)
		(property "Value" "RJ45_Abracon_ARJM11B1-502-AB-EW2"
			(at -4.3 22.78 270)
			(layer "F.Fab")
			(effects
				(font
					(size 0.7 0.7)
					(thickness 0.15)
				)
				(justify left bottom)
			)
		)
		(property "Datasheet" "https://www.mouser.com/datasheet/3/184/1/ARJM11.pdf"
			(at -0.035 -0.01 270)
			(layer "F.Fab")
			(effects
				(font
					(size 0.7 0.7)
					(thickness 0.15)
				)
				(justify left bottom)
			)
		)
		(property "Description" "Modular Connectors / Ethernet Connectors RJ45 JACK W/MAG 1X1 1000BASE-T"
			(at -0.035 -0.01 270)
			(layer "F.Fab")
			(effects
				(font
					(size 0.7 0.7)
					(thickness 0.15)
				)
				(justify left bottom)
			)
		)
		(property "MPN" "ARJM11B1-502-AB-EW2"
			(at 0 0 270)
			(unlocked yes)
			(layer "F.Fab")
			(hide yes)
			(effects
				(font
					(size 1 1)
					(thickness 0.15)
				)
			)
		)
		(property "Manufacturer" "Abracon"
			(at 0 0 270)
			(unlocked yes)
			(layer "F.Fab")
			(hide yes)
			(effects
				(font
					(size 1 1)
					(thickness 0.15)
				)
			)
		)
		(property "Author" "Antmicro"
			(at 0 0 270)
			(unlocked yes)
			(layer "F.Fab")
			(hide yes)
			(effects
				(font
					(size 1 1)
					(thickness 0.15)
				)
			)
		)
		(property "License" "Apache-2.0"
			(at 0 0 270)
			(unlocked yes)
			(layer "F.Fab")
			(hide yes)
			(effects
				(font
					(size 1 1)
					(thickness 0.15)
				)
			)
		)
		(sheetname "/Ethernet/")
		(sheetfile "ethernet.kicad_sch")
		(attr through_hole)
		(fp_line
			(start -2.235 19.69)
			(end 13.665 19.69)
			(stroke
				(width 0.15)
				(type solid)
			)
			(layer "F.SilkS")
		)
		(fp_line
			(start -2.235 19.69)
			(end -2.235 7.48)
			(stroke
				(width 0.15)
				(type solid)
			)
			(layer "F.SilkS")
		)
		(fp_line
			(start 13.665 19.69)
			(end 13.665 7.48)
			(stroke
				(width 0.15)
				(type solid)
			)
			(layer "F.SilkS")
		)
		(fp_line
			(start 13.665 4.19)
			(end 13.665 -1.51)
			(stroke
				(width 0.15)
				(type solid)
			)
			(layer "F.SilkS")
		)
		(fp_line
			(start -2.235 -1.51)
			(end -2.235 4.19)
			(stroke
				(width 0.15)
				(type solid)
			)
			(layer "F.SilkS")
		)
		(fp_line
			(start 13.665 -1.51)
			(end -2.235 -1.51)
			(stroke
				(width 0.15)
				(type solid)
			)
			(layer "F.SilkS")
		)
		(fp_line
			(start -3.7 19.94)
			(end 15.12 19.94)
			(stroke
				(width 0.05)
				(type solid)
			)
			(layer "F.CrtYd")
		)
		(fp_line
			(start 15.12 19.94)
			(end 15.12 -1.76)
			(stroke
				(width 0.05)
				(type solid)
			)
			(layer "F.CrtYd")
		)
		(fp_line
			(start -3.7 -1.76)
			(end -3.7 19.94)
			(stroke
				(width 0.05)
				(type solid)
			)
			(layer "F.CrtYd")
		)
		(fp_line
			(start 15.12 -1.76)
			(end -3.7 -1.76)
			(stroke
				(width 0.05)
				(type solid)
			)
			(layer "F.CrtYd")
		)
		(fp_line
			(start -2.235 19.69)
			(end 13.665 19.69)
			(stroke
				(width 0.15)
				(type solid)
			)
			(layer "F.Fab")
		)
		(fp_line
			(start 13.665 19.69)
			(end 13.665 -1.51)
			(stroke
				(width 0.15)
				(type solid)
			)
			(layer "F.Fab")
		)
		(fp_line
			(start -2.235 -1.51)
			(end -2.235 19.69)
			(stroke
				(width 0.15)
				(type solid)
			)
			(layer "F.Fab")
		)
		(fp_line
			(start 13.665 -1.51)
			(end -2.235 -1.51)
			(stroke
				(width 0.15)
				(type solid)
			)
			(layer "F.Fab")
		)
		(fp_text user "Author: Antmicro"
			(at -4.3 23.98 270)
			(layer "F.Fab")
			(effects
				(font
					(size 0.7 0.7)
					(thickness 0.15)
				)
				(justify left bottom)
			)
		)
		(fp_text user "License: Apache-2.0"
			(at -4.3 25.18 270)
			(layer "F.Fab")
			(effects
				(font
					(size 0.7 0.7)
					(thickness 0.15)
				)
				(justify left bottom)
			)
		)
		(fp_text user "${REFERENCE}"
			(at -4.26 21.29 270)
			(layer "F.Fab")
			(effects
				(font
					(size 0.7 0.7)
					(thickness 0.15)
				)
				(justify left bottom)
			)
		)
		(pad "" np_thru_hole circle
			(at 0 8.89 270)
			(size 3.2 3.2)
			(drill 3.25)
			(layers "*.Cu" "*.Mask")
		)
		(pad "" np_thru_hole circle
			(at 11.43 8.89 270)
			(size 3.2 3.2)
			(drill 3.25)
			(layers "*.Cu" "*.Mask")
		)
		(pad "1" thru_hole circle
			(at 0 0 270)
			(size 1.458 1.458)
			(drill 0.9)
			(layers "*.Cu" "*.Mask")
			(remove_unused_layers no)
			(net 88 "/Ethernet/ETH1_P")
			(pinfunction "1")
			(pintype "bidirectional")
			(solder_mask_margin 0)
		)
		(pad "2" thru_hole circle
			(at 1.27 2.54 270)
			(size 1.458 1.458)
			(drill 0.9)
			(layers "*.Cu" "*.Mask")
			(remove_unused_layers no)
			(net 91 "/Ethernet/ETH1_N")
			(pinfunction "2")
			(pintype "bidirectional")
			(solder_mask_margin 0)
		)
		(pad "3" thru_hole circle
			(at 2.54 0 270)
			(size 1.458 1.458)
			(drill 0.9)
			(layers "*.Cu" "*.Mask")
			(remove_unused_layers no)
			(net 87 "/Ethernet/ETH2_P")
			(pinfunction "3")
			(pintype "bidirectional")
			(solder_mask_margin 0)
		)
		(pad "4" thru_hole circle
			(at 3.81 2.54 270)
			(size 1.458 1.458)
			(drill 0.9)
			(layers "*.Cu" "*.Mask")
			(remove_unused_layers no)
			(net 90 "/Ethernet/ETH2_N")
			(pinfunction "4")
			(pintype "bidirectional")
			(solder_mask_margin 0)
		)
		(pad "5" thru_hole circle
			(at 5.08 0 270)
			(size 1.458 1.458)
			(drill 0.9)
			(layers "*.Cu" "*.Mask")
			(remove_unused_layers no)
			(net 821 "Net-(C135-Pad2)")
			(pinfunction "5")
			(pintype "passive")
			(solder_mask_margin 0)
		)
		(pad "6" thru_hole circle
			(at 6.35 2.54 270)
			(size 1.458 1.458)
			(drill 0.9)
			(layers "*.Cu" "*.Mask")
			(remove_unused_layers no)
			(net 822 "Net-(C137-Pad2)")
			(pinfunction "6")
			(pintype "passive")
			(solder_mask_margin 0)
		)
		(pad "7" thru_hole circle
			(at 7.62 0 270)
			(size 1.458 1.458)
			(drill 0.9)
			(layers "*.Cu" "*.Mask")
			(remove_unused_layers no)
			(net 86 "/Ethernet/ETH3_P")
			(pinfunction "7")
			(pintype "bidirectional")
			(solder_mask_margin 0)
		)
		(pad "8" thru_hole circle
			(at 8.89 2.54 270)
			(size 1.458 1.458)
			(drill 0.9)
			(layers "*.Cu" "*.Mask")
			(remove_unused_layers no)
			(net 92 "/Ethernet/ETH3_N")
			(pinfunction "8")
			(pintype "bidirectional")
			(solder_mask_margin 0)
		)
		(pad "9" thru_hole circle
			(at 10.16 0 270)
			(size 1.458 1.458)
			(drill 0.9)
			(layers "*.Cu" "*.Mask")
			(remove_unused_layers no)
			(net 89 "/Ethernet/ETH4_P")
			(pinfunction "9")
			(pintype "bidirectional")
			(solder_mask_margin 0)
		)
		(pad "10" thru_hole circle
			(at 11.43 2.54 270)
			(size 1.458 1.458)
			(drill 0.9)
			(layers "*.Cu" "*.Mask")
			(remove_unused_layers no)
			(net 93 "/Ethernet/ETH4_N")
			(pinfunction "10")
			(pintype "bidirectional")
			(solder_mask_margin 0)
		)
		(pad "11" thru_hole circle
			(at -0.96 12.95 270)
			(size 1.605 1.605)
			(drill 1.02)
			(layers "*.Cu" "*.Mask")
			(remove_unused_layers no)
			(net 823 "Net-(J6-LED_G+)")
			(pinfunction "LED_G+")
			(pintype "passive")
			(solder_mask_margin 0)
		)
		(pad "12" thru_hole circle
			(at 1.58 12.95 270)
			(size 1.605 1.605)
			(drill 1.02)
			(layers "*.Cu" "*.Mask")
			(remove_unused_layers no)
			(net 330 "/Ethernet/LED_SPD")
			(pinfunction "LED_G-")
			(pintype "passive")
			(solder_mask_margin 0)
		)
		(pad "13" thru_hole circle
			(at 9.85 12.95 270)
			(size 1.605 1.605)
			(drill 1.02)
			(layers "*.Cu" "*.Mask")
			(remove_unused_layers no)
			(net 824 "Net-(J6-LED_Y+)")
			(pinfunction "LED_Y+")
			(pintype "passive")
			(solder_mask_margin 0)
		)
		(pad "14" thru_hole circle
			(at 12.39 12.95 270)
			(size 1.605 1.605)
			(drill 1.02)
			(layers "*.Cu" "*.Mask")
			(remove_unused_layers no)
			(net 331 "/Ethernet/LED_LINK")
			(pinfunction "LED_Y-")
			(pintype "passive")
			(solder_mask_margin 0)
		)
		(pad "SH" thru_hole circle
			(at -2.135 5.84 270)
			(size 2.625 2.625)
			(drill 1.7)
			(layers "*.Cu" "*.Mask")
			(remove_unused_layers no)
			(net 31 "Net-(C234-Pad1)")
			(pinfunction "SH")
			(pintype "passive")
			(solder_mask_margin 0)
		)
		(pad "SH" thru_hole circle
			(at 13.565 5.84 270)
			(size 2.625 2.625)
			(drill 1.7)
			(layers "*.Cu" "*.Mask")
			(remove_unused_layers no)
			(net 31 "Net-(C234-Pad1)")
			(pinfunction "SH")
			(pintype "passive")
			(solder_mask_margin 0)
		)
	)
	(footprint "antmicro-footprints:L_0402_1005Metric"
		(layer "F.Cu")
		(at 121.025 149.61 180)
		(descr "Inductor SMD 0402")
		(tags "Inductor SMD 0402")
		(property "Reference" "L3"
			(at -5.375 -0.435 0)
			(layer "F.SilkS")
			(effects
				(font
					(size 0.7 0.7)
					(thickness 0.15)
				)
				(justify right bottom)
			)
		)
		(property "Value" "L_20n_0.35A_0402"
			(at 0 1.4 0)
			(layer "F.Fab")
			(effects
				(font
					(size 0.7 0.7)
					(thickness 0.15)
				)
				(justify right bottom)
			)
		)
		(property "Datasheet" "https://product.tdk.com/system/files/dam/doc/product/inductor/inductor/smd/catalog/inductor_automotive_high-frequency_mlg1005s_en.pdf?ref_disty=mouser"
			(at 0 0 180)
			(layer "F.Fab")
			(hide yes)
			(effects
				(font
					(size 1.27 1.27)
					(thickness 0.15)
				)
			)
		)
		(property "Val" "20n/0.35A"
			(at 0 0 180)
			(unlocked yes)
			(layer "F.Fab")
			(hide yes)
			(effects
				(font
					(size 1 1)
					(thickness 0.15)
				)
			)
		)
		(property "Manufacturer" "TDK"
			(at 0 0 180)
			(unlocked yes)
			(layer "F.Fab")
			(hide yes)
			(effects
				(font
					(size 1 1)
					(thickness 0.15)
				)
			)
		)
		(property "MPN" "MLG1005S20NJTD25"
			(at 0 0 180)
			(unlocked yes)
			(layer "F.Fab")
			(hide yes)
			(effects
				(font
					(size 1 1)
					(thickness 0.15)
				)
			)
		)
		(property "ISat" ""
			(at 0 0 180)
			(unlocked yes)
			(layer "F.Fab")
			(hide yes)
			(effects
				(font
					(size 1 1)
					(thickness 0.15)
				)
			)
		)
		(property "IMax" "0.35 A"
			(at 0 0 180)
			(unlocked yes)
			(layer "F.Fab")
			(hide yes)
			(effects
				(font
					(size 1 1)
					(thickness 0.15)
				)
			)
		)
		(property "Size" "1.0x0.5"
			(at 0 0 180)
			(unlocked yes)
			(layer "F.Fab")
			(hide yes)
			(effects
				(font
					(size 1 1)
					(thickness 0.15)
				)
			)
		)
		(property "Author" "Antmicro"
			(at 0 0 180)
			(unlocked yes)
			(layer "F.Fab")
			(hide yes)
			(effects
				(font
					(size 1 1)
					(thickness 0.15)
				)
			)
		)
		(property "License" "Apache-2.0"
			(at 0 0 180)
			(unlocked yes)
			(layer "F.Fab")
			(hide yes)
			(effects
				(font
					(size 1 1)
					(thickness 0.15)
				)
			)
		)
		(sheetname "/HDMI + SD Card/")
		(sheetfile "hdmi-sd-card.kicad_sch")
		(attr smd)
		(fp_rect
			(start -0.925 -0.47)
			(end 0.925 0.47)
			(stroke
				(width 0.05)
				(type default)
			)
			(fill no)
			(layer "F.CrtYd")
		)
		(fp_rect
			(start -0.499 -0.249)
			(end 0.499 0.249)
			(stroke
				(width 0.15)
				(type solid)
			)
			(fill no)
			(layer "F.Fab")
		)
		(fp_text user "${REFERENCE}"
			(at -0.932 3.168 180)
			(layer "F.Fab")
			(effects
				(font
					(size 0.7 0.7)
					(thickness 0.15)
				)
				(justify left bottom)
			)
		)
		(fp_text user "License: Apache-2.0"
			(at -0.932 5.17 180)
			(layer "F.Fab")
			(effects
				(font
					(size 0.7 0.7)
					(thickness 0.15)
				)
				(justify left bottom)
			)
		)
		(fp_text user "Author: Antmicro"
			(at -0.932 4.17 180)
			(layer "F.Fab")
			(effects
				(font
					(size 0.7 0.7)
					(thickness 0.15)
				)
				(justify left bottom)
			)
		)
		(pad "1" smd roundrect
			(at -0.48 0 180)
			(size 0.59 0.64)
			(layers "F.Cu" "F.Mask" "F.Paste")
			(roundrect_rratio 0.25)
			(net 348 "/FPGA MGT Interface/HDMI_IN.D1_P")
			(pintype "passive")
		)
		(pad "2" smd roundrect
			(at 0.48 0 180)
			(size 0.59 0.64)
			(layers "F.Cu" "F.Mask" "F.Paste")
			(roundrect_rratio 0.25)
			(net 673 "Net-(L3-Pad2)")
			(pintype "passive")
		)
	)
)
